# BASEBOARD_FAB2 (Tioga Pass) — schematic netlist excerpt (pin names and nets, part order shuffled) for the footprints in the layout excerpt that follows; sources: Cadence DE-HDL packaged netlist, KiCad conversion of Wiwynn_Tioga_Pass_MB.brd

R1C35  RES  3.32K 1% EMPTY  pkg 0402  page 156 : A = P3V3_STBY ; B = FM_CPU1_SM_WP
C7G31  CAP  0.220UF 16V 10% X7R  pkg 0402  page 216 : A = VR_PVDDQ_ABC_PH1_BOOT ; B = VR_PVDDQ_ABC_PH1_PHASE
C4G21  CAP  1.0UF 16V 10% X6S  pkg 0402  page 229 : A = VR_PVTT_GHJ_VREF ; B = GND

(kicad_pcb
	(version 20260206)
	(generator "pcbnew")
	(generator_version "10.0")
	(general
		(thickness 1.6)
		(legacy_teardrops no)
	)
	(paper "A4")
	(title_block
		(title "Wiwynn_Tioga_Pass_MB.brd")
		(comment 1 "Tioga Pass / footprints 1109-1111 of 4770")
	)
	(layers
		(0 "F.Cu" signal "TOP")
		(4 "In1.Cu" signal "L2GND")
		(6 "In2.Cu" signal "L3")
		(8 "In3.Cu" signal "L4GND")
		(10 "In4.Cu" signal "L5")
		(12 "In5.Cu" signal "L6GND")
		(14 "In6.Cu" signal "L7VCC")
		(16 "In7.Cu" signal "L8VCC")
		(18 "In8.Cu" signal "L9GND")
		(20 "In9.Cu" signal "L10")
		(22 "In10.Cu" signal "L11GND")
		(24 "In11.Cu" signal "L12")
		(26 "In12.Cu" signal "L13GND")
		(2 "B.Cu" signal "BOTTOM")
		(9 "F.Adhes" user "F.Adhesive")
		(11 "B.Adhes" user "B.Adhesive")
		(13 "F.Paste" user "Package Geometry/Pastemask Top")
		(15 "B.Paste" user "Package Geometry/Pastemask Bottom")
		(5 "F.SilkS" user "Ref Des/Silkscreen Top")
		(7 "B.SilkS" user "Ref Des/Silkscreen Bottom")
		(1 "F.Mask" user "Board Geometry/Soldermask Top")
		(3 "B.Mask" user "Board Geometry/Soldermask Bottom")
		(17 "Dwgs.User" user "User.Drawings")
		(19 "Cmts.User" user "User.Comments")
		(21 "Eco1.User" user "User.Eco1")
		(23 "Eco2.User" user "User.Eco2")
		(25 "Edge.Cuts" user "Board Geometry/Outline")
		(27 "Margin" user)
		(31 "F.CrtYd" user "Package Geometry/Place Bound Top")
		(29 "B.CrtYd" user "Package Geometry/Place Bound Bottom")
		(35 "F.Fab" user "Ref Des/Assembly Top")
		(33 "B.Fab" user "Ref Des/Assembly Bottom")
	)
	(footprint ""
		(layer "F.Cu")
		(at 173.609 -2.794 90)
		(property "Reference" "C4G21"
			(at 0 0 90)
			(layer "F.SilkS")
			(hide yes)
			(effects
				(font
					(size 1.27 1.27)
				)
			)
		)
		(property "Value" ""
			(at 0 0 90)
			(layer "F.Fab")
			(effects
				(font
					(size 1.27 1.27)
				)
			)
		)
		(duplicate_pad_numbers_are_jumpers no)
		(fp_rect
			(start 0.3048 0.9906)
			(end -0.3048 -0.1016)
			(stroke
				(width 0)
				(type default)
			)
			(fill no)
			(layer "F.CrtYd")
		)
		(fp_line
			(start 0.3048 -0.1016)
			(end -0.3048 -0.1016)
			(stroke
				(width 0.1)
				(type default)
			)
			(layer "F.Fab")
		)
		(fp_line
			(start -0.3048 -0.1016)
			(end -0.3048 0.9906)
			(stroke
				(width 0.1)
				(type default)
			)
			(layer "F.Fab")
		)
		(fp_line
			(start 0.3048 0.9906)
			(end 0.3048 -0.1016)
			(stroke
				(width 0.1)
				(type default)
			)
			(layer "F.Fab")
		)
		(fp_line
			(start -0.3048 0.9906)
			(end 0.3048 0.9906)
			(stroke
				(width 0.1)
				(type default)
			)
			(layer "F.Fab")
		)
		(pad "1" smd rect
			(at 0 0 90)
			(size 0.508 0.508)
			(layers "F.Cu" "F.Mask" "F.Paste")
			(net "VR_PVTT_GHJ_VREF")
		)
		(pad "2" smd rect
			(at 0 0.889 90)
			(size 0.508 0.508)
			(layers "F.Cu" "F.Mask" "F.Paste")
			(net "GND")
		)
		(zone
			(layer "F.Cu")
			(hatch none 0.5)
			(connect_pads
				(clearance 0)
			)
			(min_thickness 0.25)
			(keepout
				(tracks not_allowed)
				(vias allowed)
				(pads allowed)
				(copperpour not_allowed)
				(footprints allowed)
			)
			(placement
				(enabled no)
				(sheetname "")
			)
			(fill
				(thermal_gap 0.5)
				(thermal_bridge_width 0.5)
				(island_removal_mode 0)
			)
			(polygon
				(pts
					(xy 174.244 -3.048) (xy 173.863 -3.048) (xy 173.863 -2.54) (xy 174.244 -2.54)
				)
			)
		)
		(zone
			(layer "F.Cu")
			(hatch none 0.5)
			(connect_pads
				(clearance 0)
			)
			(min_thickness 0.25)
			(keepout
				(tracks allowed)
				(vias not_allowed)
				(pads allowed)
				(copperpour not_allowed)
				(footprints allowed)
			)
			(placement
				(enabled no)
				(sheetname "")
			)
			(fill
				(thermal_gap 0.5)
				(thermal_bridge_width 0.5)
				(island_removal_mode 0)
			)
			(polygon
				(pts
					(xy 174.244 -3.048) (xy 173.863 -3.048) (xy 173.863 -2.54) (xy 174.244 -2.54)
				)
			)
		)
	)
	(footprint ""
		(layer "F.Cu")
		(at 28.7528 -102.997 90)
		(property "Reference" "R1C35"
			(at 0 0 90)
			(layer "F.SilkS")
			(hide yes)
			(effects
				(font
					(size 1.27 1.27)
				)
			)
		)
		(property "Value" ""
			(at 0 0 90)
			(layer "F.Fab")
			(effects
				(font
					(size 1.27 1.27)
				)
			)
		)
		(duplicate_pad_numbers_are_jumpers no)
		(fp_poly
			(pts
				(xy -0.2794 -0.1016) (xy 0.2794 -0.1016) (xy 0.2794 0.9906) (xy -0.2794 0.9906)
			)
			(stroke
				(width 0)
				(type default)
			)
			(fill no)
			(layer "F.CrtYd")
		)
		(fp_line
			(start 0.2794 -0.1016)
			(end -0.2794 -0.1016)
			(stroke
				(width 0.1)
				(type default)
			)
			(layer "F.Fab")
		)
		(fp_line
			(start -0.2794 -0.1016)
			(end -0.2794 0.9906)
			(stroke
				(width 0.1)
				(type default)
			)
			(layer "F.Fab")
		)
		(fp_line
			(start 0.2794 0.9906)
			(end 0.2794 -0.1016)
			(stroke
				(width 0.1)
				(type default)
			)
			(layer "F.Fab")
		)
		(fp_line
			(start -0.2794 0.9906)
			(end 0.2794 0.9906)
			(stroke
				(width 0.1)
				(type default)
			)
			(layer "F.Fab")
		)
		(pad "1" smd rect
			(at 0 0 90)
			(size 0.508 0.508)
			(layers "F.Cu" "F.Mask" "F.Paste")
			(net "P3V3_STBY")
		)
		(pad "2" smd rect
			(at 0 0.889 90)
			(size 0.508 0.508)
			(layers "F.Cu" "F.Mask" "F.Paste")
			(net "FM_CPU1_SM_WP")
		)
		(zone
			(layer "F.Cu")
			(hatch none 0.5)
			(connect_pads
				(clearance 0)
			)
			(min_thickness 0.25)
			(keepout
				(tracks allowed)
				(vias not_allowed)
				(pads allowed)
				(copperpour not_allowed)
				(footprints allowed)
			)
			(placement
				(enabled no)
				(sheetname "")
			)
			(fill
				(thermal_gap 0.5)
				(thermal_bridge_width 0.5)
				(island_removal_mode 0)
			)
			(polygon
				(pts
					(xy 29.0068 -102.743) (xy 29.0068 -103.251) (xy 29.3878 -103.251) (xy 29.3878 -102.743)
				)
			)
		)
		(zone
			(layer "F.Cu")
			(hatch none 0.5)
			(connect_pads
				(clearance 0)
			)
			(min_thickness 0.25)
			(keepout
				(tracks not_allowed)
				(vias allowed)
				(pads allowed)
				(copperpour not_allowed)
				(footprints allowed)
			)
			(placement
				(enabled no)
				(sheetname "")
			)
			(fill
				(thermal_gap 0.5)
				(thermal_bridge_width 0.5)
				(island_removal_mode 0)
			)
			(polygon
				(pts
					(xy 29.3878 -102.743) (xy 29.3878 -103.251) (xy 29.0068 -103.251) (xy 29.0068 -102.743)
				)
			)
		)
	)
	(footprint ""
		(layer "F.Cu")
		(at 350.407224 -4.167378 180)
		(property "Reference" "C7G31"
			(at 0 0 180)
			(layer "F.SilkS")
			(hide yes)
			(effects
				(font
					(size 1.27 1.27)
				)
			)
		)
		(property "Value" ""
			(at 0 0 180)
			(layer "F.Fab")
			(effects
				(font
					(size 1.27 1.27)
				)
			)
		)
		(duplicate_pad_numbers_are_jumpers no)
		(fp_poly
			(pts
				(xy 0.3048 -0.1016) (xy 0.3048 0.9906) (xy -0.3048 0.9906) (xy -0.3048 -0.1016)
			)
			(stroke
				(width 0)
				(type default)
			)
			(fill no)
			(layer "F.CrtYd")
		)
		(fp_line
			(start 0.3048 0.9906)
			(end 0.3048 -0.1016)
			(stroke
				(width 0.1)
				(type default)
			)
			(layer "F.Fab")
		)
		(fp_line
			(start 0.3048 -0.1016)
			(end -0.3048 -0.1016)
			(stroke
				(width 0.1)
				(type default)
			)
			(layer "F.Fab")
		)
		(fp_line
			(start -0.3048 0.9906)
			(end 0.3048 0.9906)
			(stroke
				(width 0.1)
				(type default)
			)
			(layer "F.Fab")
		)
		(fp_line
			(start -0.3048 -0.1016)
			(end -0.3048 0.9906)
			(stroke
				(width 0.1)
				(type default)
			)
			(layer "F.Fab")
		)
		(pad "1" smd rect
			(at 0 0 180)
			(size 0.508 0.508)
			(layers "F.Cu" "F.Mask" "F.Paste")
			(net "VR_PVDDQ_ABC_PH1_BOOT")
		)
		(pad "2" smd rect
			(at 0 0.889 180)
			(size 0.508 0.508)
			(layers "F.Cu" "F.Mask" "F.Paste")
			(net "VR_PVDDQ_ABC_PH1_PHASE")
		)
		(zone
			(layer "F.Cu")
			(hatch none 0.5)
			(connect_pads
				(clearance 0)
			)
			(min_thickness 0.25)
			(keepout
				(tracks not_allowed)
				(vias allowed)
				(pads allowed)
				(copperpour not_allowed)
				(footprints allowed)
			)
			(placement
				(enabled no)
				(sheetname "")
			)
			(fill
				(thermal_gap 0.5)
				(thermal_bridge_width 0.5)
				(island_removal_mode 0)
			)
			(polygon
				(pts
					(xy 350.661224 -4.802378) (xy 350.153224 -4.802378) (xy 350.153224 -4.421378) (xy 350.661224 -4.421378)
				)
			)
		)
		(zone
			(layer "F.Cu")
			(hatch none 0.5)
			(connect_pads
				(clearance 0)
			)
			(min_thickness 0.25)
			(keepout
				(tracks allowed)
				(vias not_allowed)
				(pads allowed)
				(copperpour not_allowed)
				(footprints allowed)
			)
			(placement
				(enabled no)
				(sheetname "")
			)
			(fill
				(thermal_gap 0.5)
				(thermal_bridge_width 0.5)
				(island_removal_mode 0)
			)
			(polygon
				(pts
					(xy 350.661224 -4.421378) (xy 350.153224 -4.421378) (xy 350.153224 -4.802378) (xy 350.661224 -4.802378)
				)
			)
		)
	)
)
